(kicad_pcb
	(version 20260206)
	(generator "pcbnew")
	(generator_version "10.0")
	(general
		(thickness 1.6)
		(legacy_teardrops no)
	)
	(paper "A4")
	(title_block
		(title "04192023_DAF0TMB3IC0_F0TG_MB_C_brd_V02_OCP.brd")
		(comment 1 "Grand Teton / footprints 3828-3832 of 8354")
	)
	(layers
		(0 "F.Cu" signal "TOP")
		(4 "In1.Cu" signal "GND")
		(6 "In2.Cu" signal "IN1")
		(8 "In3.Cu" signal "GND1")
		(10 "In4.Cu" signal "IN2")
		(12 "In5.Cu" signal "GND2")
		(14 "In6.Cu" signal "IN3")
		(16 "In7.Cu" signal "GND3")
		(18 "In8.Cu" signal "VCC")
		(20 "In9.Cu" signal "VCC1")
		(22 "In10.Cu" signal "GND4")
		(24 "In11.Cu" signal "IN4")
		(26 "In12.Cu" signal "GND5")
		(28 "In13.Cu" signal "IN5")
		(30 "In14.Cu" signal "GND6")
		(32 "In15.Cu" signal "IN6")
		(34 "In16.Cu" signal "GND7")
		(2 "B.Cu" signal "BOTTOM")
		(9 "F.Adhes" user "F.Adhesive")
		(11 "B.Adhes" user "B.Adhesive")
		(13 "F.Paste" user "Package Geometry/Pastemask Top")
		(15 "B.Paste" user "Package Geometry/Pastemask Bottom")
		(5 "F.SilkS" user "Ref Des/Silkscreen Top")
		(7 "B.SilkS" user "Ref Des/Silkscreen Bottom")
		(1 "F.Mask" user "Board Geometry/Soldermask Top")
		(3 "B.Mask" user "Board Geometry/Soldermask Bottom")
		(17 "Dwgs.User" user "User.Drawings")
		(19 "Cmts.User" user "User.Comments")
		(21 "Eco1.User" user "User.Eco1")
		(23 "Eco2.User" user "User.Eco2")
		(25 "Edge.Cuts" user "Board Geometry/Outline")
		(27 "Margin" user)
		(31 "F.CrtYd" user "Package Geometry/Place Bound Top")
		(29 "B.CrtYd" user "Package Geometry/Place Bound Bottom")
		(35 "F.Fab" user "Ref Des/Assembly Top")
		(33 "B.Fab" user "Ref Des/Assembly Bottom")
	)
	(footprint ""
		(layer "F.Cu")
		(at 58.017918 -83.554062)
		(property "Reference" "ME1"
			(at 0.1016 -5.9055 0)
			(unlocked yes)
			(layer "F.SilkS")
			(effects
				(font
					(size 0.254 0.127)
					(thickness 0.000001)
				)
				(justify left)
			)
		)
		(property "Value" ""
			(at 0 0 0)
			(layer "F.Fab")
			(effects
				(font
					(size 1.27 1.27)
				)
			)
		)
		(duplicate_pad_numbers_are_jumpers no)
	)
	(footprint ""
		(layer "F.Cu")
		(at 193.48958 -413.964882 90)
		(property "Reference" "R3770"
			(at 0 0 90)
			(layer "F.SilkS")
			(hide yes)
			(effects
				(font
					(size 1.27 1.27)
				)
			)
		)
		(property "Value" ""
			(at 0 0 90)
			(layer "F.Fab")
			(effects
				(font
					(size 1.27 1.27)
				)
			)
		)
		(duplicate_pad_numbers_are_jumpers no)
		(fp_line
			(start 0.7874 -0.4064)
			(end 0.7874 0.4064)
			(stroke
				(width 0.1524)
				(type default)
			)
			(layer "F.SilkS")
		)
		(fp_line
			(start -0.7874 -0.4064)
			(end 0.7874 -0.4064)
			(stroke
				(width 0.1524)
				(type default)
			)
			(layer "F.SilkS")
		)
		(fp_line
			(start 0.7874 0.4064)
			(end -0.7874 0.4064)
			(stroke
				(width 0.1524)
				(type default)
			)
			(layer "F.SilkS")
		)
		(fp_line
			(start -0.7874 0.4064)
			(end -0.7874 -0.4064)
			(stroke
				(width 0.1524)
				(type default)
			)
			(layer "F.SilkS")
		)
		(fp_line
			(start -0.12065 -0.305054)
			(end -0.12065 -0.2794)
			(stroke
				(width 0.1)
				(type default)
			)
			(layer "F.Fab")
		)
		(fp_line
			(start -0.67945 -0.305054)
			(end -0.12065 -0.305054)
			(stroke
				(width 0.1)
				(type default)
			)
			(layer "F.Fab")
		)
		(fp_line
			(start 0.67945 -0.3048)
			(end 0.67945 0.3048)
			(stroke
				(width 0.1)
				(type default)
			)
			(layer "F.Fab")
		)
		(fp_line
			(start 0.12065 -0.3048)
			(end 0.67945 -0.3048)
			(stroke
				(width 0.1)
				(type default)
			)
			(layer "F.Fab")
		)
		(fp_line
			(start 0.12065 -0.2794)
			(end 0.12065 -0.3048)
			(stroke
				(width 0.1)
				(type default)
			)
			(layer "F.Fab")
		)
		(fp_line
			(start -0.12065 -0.2794)
			(end 0.12065 -0.2794)
			(stroke
				(width 0.1)
				(type default)
			)
			(layer "F.Fab")
		)
		(fp_line
			(start 0.120396 0.2794)
			(end -0.12065 0.2794)
			(stroke
				(width 0.1)
				(type default)
			)
			(layer "F.Fab")
		)
		(fp_line
			(start -0.12065 0.2794)
			(end -0.12065 0.3048)
			(stroke
				(width 0.1)
				(type default)
			)
			(layer "F.Fab")
		)
		(fp_line
			(start 0.67945 0.3048)
			(end 0.120396 0.3048)
			(stroke
				(width 0.1)
				(type default)
			)
			(layer "F.Fab")
		)
		(fp_line
			(start 0.120396 0.3048)
			(end 0.120396 0.2794)
			(stroke
				(width 0.1)
				(type default)
			)
			(layer "F.Fab")
		)
		(fp_line
			(start -0.12065 0.3048)
			(end -0.67945 0.3048)
			(stroke
				(width 0.1)
				(type default)
			)
			(layer "F.Fab")
		)
		(fp_line
			(start -0.67945 0.3048)
			(end -0.67945 -0.305054)
			(stroke
				(width 0.1)
				(type default)
			)
			(layer "F.Fab")
		)
		(pad "1" smd circle
			(at -0.40005 0 90)
			(size 0 0)
			(layers "F.Cu" "F.Mask" "F.Paste")
			(net "GPU_PRSNT")
		)
		(pad "2" smd circle
			(at 0.40005 0 90)
			(size 0 0)
			(layers "F.Cu" "F.Mask" "F.Paste")
			(net "GPU_PRSNT_R")
		)
	)
	(footprint ""
		(layer "F.Cu")
		(at 80.550512 -339.644736 -90)
		(property "Reference" "PC386"
			(at 0 0 270)
			(layer "F.SilkS")
			(hide yes)
			(effects
				(font
					(size 1.27 1.27)
				)
			)
		)
		(property "Value" ""
			(at 0 0 270)
			(layer "F.Fab")
			(effects
				(font
					(size 1.27 1.27)
				)
			)
		)
		(duplicate_pad_numbers_are_jumpers no)
		(fp_line
			(start -0.7874 0.4064)
			(end -0.7874 -0.4064)
			(stroke
				(width 0.1524)
				(type default)
			)
			(layer "F.SilkS")
		)
		(fp_line
			(start 0.7874 0.4064)
			(end -0.7874 0.4064)
			(stroke
				(width 0.1524)
				(type default)
			)
			(layer "F.SilkS")
		)
		(fp_line
			(start -0.7874 -0.4064)
			(end 0.7874 -0.4064)
			(stroke
				(width 0.1524)
				(type default)
			)
			(layer "F.SilkS")
		)
		(fp_line
			(start 0.7874 -0.4064)
			(end 0.7874 0.4064)
			(stroke
				(width 0.1524)
				(type default)
			)
			(layer "F.SilkS")
		)
		(fp_line
			(start -0.67945 0.3048)
			(end -0.67945 -0.305054)
			(stroke
				(width 0.1)
				(type default)
			)
			(layer "F.Fab")
		)
		(fp_line
			(start -0.12065 0.3048)
			(end -0.67945 0.3048)
			(stroke
				(width 0.1)
				(type default)
			)
			(layer "F.Fab")
		)
		(fp_line
			(start 0.120396 0.3048)
			(end 0.120396 0.2794)
			(stroke
				(width 0.1)
				(type default)
			)
			(layer "F.Fab")
		)
		(fp_line
			(start 0.67945 0.3048)
			(end 0.120396 0.3048)
			(stroke
				(width 0.1)
				(type default)
			)
			(layer "F.Fab")
		)
		(fp_line
			(start -0.12065 0.2794)
			(end -0.12065 0.3048)
			(stroke
				(width 0.1)
				(type default)
			)
			(layer "F.Fab")
		)
		(fp_line
			(start 0.120396 0.2794)
			(end -0.12065 0.2794)
			(stroke
				(width 0.1)
				(type default)
			)
			(layer "F.Fab")
		)
		(fp_line
			(start -0.12065 -0.2794)
			(end 0.12065 -0.2794)
			(stroke
				(width 0.1)
				(type default)
			)
			(layer "F.Fab")
		)
		(fp_line
			(start 0.12065 -0.2794)
			(end 0.12065 -0.3048)
			(stroke
				(width 0.1)
				(type default)
			)
			(layer "F.Fab")
		)
		(fp_line
			(start 0.12065 -0.3048)
			(end 0.67945 -0.3048)
			(stroke
				(width 0.1)
				(type default)
			)
			(layer "F.Fab")
		)
		(fp_line
			(start 0.67945 -0.3048)
			(end 0.67945 0.3048)
			(stroke
				(width 0.1)
				(type default)
			)
			(layer "F.Fab")
		)
		(fp_line
			(start -0.67945 -0.305054)
			(end -0.12065 -0.305054)
			(stroke
				(width 0.1)
				(type default)
			)
			(layer "F.Fab")
		)
		(fp_line
			(start -0.12065 -0.305054)
			(end -0.12065 -0.2794)
			(stroke
				(width 0.1)
				(type default)
			)
			(layer "F.Fab")
		)
		(pad "1" smd circle
			(at -0.40005 0 270)
			(size 0 0)
			(layers "F.Cu" "F.Mask" "F.Paste")
			(net "SW_PVDDCR_CPU1_P1_BOOT2_R")
		)
		(pad "2" smd circle
			(at 0.40005 0 270)
			(size 0 0)
			(layers "F.Cu" "F.Mask" "F.Paste")
			(net "SW_PVDDCR_CPU1_P1_BOOTR2")
		)
	)
	(footprint ""
		(layer "F.Cu")
		(at 421.284654 -428.285402 -90)
		(property "Reference" "U16"
			(at 1.53289 -3.07594 90)
			(unlocked yes)
			(layer "F.SilkS")
			(effects
				(font
					(size 0.7874 0.5842)
					(thickness 0.1524)
				)
				(justify left)
			)
		)
		(property "Value" ""
			(at 0 0 270)
			(layer "F.Fab")
			(effects
				(font
					(size 1.27 1.27)
				)
			)
		)
		(duplicate_pad_numbers_are_jumpers no)
		(fp_line
			(start -1.8288 2.500122)
			(end 1.8288 2.500122)
			(stroke
				(width 0.1524)
				(type default)
			)
			(layer "F.SilkS")
		)
		(fp_line
			(start 1.8288 2.500122)
			(end 1.8288 -2.500122)
			(stroke
				(width 0.1524)
				(type default)
			)
			(layer "F.SilkS")
		)
		(fp_line
			(start 0 -1.4224)
			(end -1.077722 -2.500122)
			(stroke
				(width 0.1524)
				(type default)
			)
			(layer "F.SilkS")
		)
		(fp_line
			(start -1.8288 -2.500122)
			(end -1.8288 2.500122)
			(stroke
				(width 0.1524)
				(type default)
			)
			(layer "F.SilkS")
		)
		(fp_line
			(start -1.077722 -2.500122)
			(end -1.8288 -2.500122)
			(stroke
				(width 0.1524)
				(type default)
			)
			(layer "F.SilkS")
		)
		(fp_line
			(start 1.077722 -2.500122)
			(end 0 -1.4224)
			(stroke
				(width 0.1524)
				(type default)
			)
			(layer "F.SilkS")
		)
		(fp_line
			(start 1.8288 -2.500122)
			(end 1.077722 -2.500122)
			(stroke
				(width 0.1524)
				(type default)
			)
			(layer "F.SilkS")
		)
		(fp_poly
			(pts
				(xy -4.5085 -2.413) (xy -4.5085 -1.397) (xy -3.4925 -1.905)
			)
			(stroke
				(width 0)
				(type default)
			)
			(fill yes)
			(layer "F.SilkS")
		)
		(fp_line
			(start -1.999996 2.500122)
			(end 1.999996 2.500122)
			(stroke
				(width 0.1)
				(type default)
			)
			(layer "F.Fab")
		)
		(fp_line
			(start 1.999996 2.500122)
			(end 1.999996 -2.500122)
			(stroke
				(width 0.1)
				(type default)
			)
			(layer "F.Fab")
		)
		(fp_line
			(start -1.999996 -2.500122)
			(end -1.999996 2.500122)
			(stroke
				(width 0.1)
				(type default)
			)
			(layer "F.Fab")
		)
		(fp_line
			(start 1.999996 -2.500122)
			(end -1.999996 -2.500122)
			(stroke
				(width 0.1)
				(type default)
			)
			(layer "F.Fab")
		)
		(fp_poly
			(pts
				(xy -4.5085 -2.413) (xy -4.5085 -1.397) (xy -3.4925 -1.905)
			)
			(stroke
				(width 0)
				(type default)
			)
			(fill yes)
			(layer "F.Fab")
		)
		(pad "1" smd rect
			(at -2.599944 -1.905 180)
			(size 0.889 1.27)
			(layers "F.Cu" "F.Mask" "F.Paste")
			(net "Net_10841")
		)
		(pad "2" smd rect
			(at -2.599944 -0.635 180)
			(size 0.889 1.27)
			(layers "F.Cu" "F.Mask" "F.Paste")
			(net "Net_10840")
		)
		(pad "3" smd rect
			(at -2.599944 0.635 180)
			(size 0.889 1.27)
			(layers "F.Cu" "F.Mask" "F.Paste")
			(net "U16_E2")
		)
		(pad "4" smd rect
			(at -2.599944 1.905 180)
			(size 0.889 1.27)
			(layers "F.Cu" "F.Mask" "F.Paste")
			(net "GND")
		)
		(pad "5" smd rect
			(at 2.599944 1.905 180)
			(size 0.889 1.27)
			(layers "F.Cu" "F.Mask" "F.Paste")
			(net "SMB_RT_CPU0_P2_ROM_SDA")
		)
		(pad "6" smd rect
			(at 2.599944 0.635 180)
			(size 0.889 1.27)
			(layers "F.Cu" "F.Mask" "F.Paste")
			(net "SMB_RT_CPU0_P2_ROM_SCL")
		)
		(pad "7" smd rect
			(at 2.599944 -0.635 180)
			(size 0.889 1.27)
			(layers "F.Cu" "F.Mask" "F.Paste")
			(net "GND")
		)
		(pad "8" smd rect
			(at 2.599944 -1.905 180)
			(size 0.889 1.27)
			(layers "F.Cu" "F.Mask" "F.Paste")
			(net "P1V8_CPU0_RT_1D")
		)
	)
	(footprint ""
		(layer "F.Cu")
		(at 304.419 -366.395)
		(property "Reference" "R8071"
			(at 0 0 0)
			(layer "F.SilkS")
			(hide yes)
			(effects
				(font
					(size 1.27 1.27)
				)
			)
		)
		(property "Value" ""
			(at 0 0 0)
			(layer "F.Fab")
			(effects
				(font
					(size 1.27 1.27)
				)
			)
		)
		(duplicate_pad_numbers_are_jumpers no)
		(fp_line
			(start -0.7874 -0.4064)
			(end 0.7874 -0.4064)
			(stroke
				(width 0.1524)
				(type default)
			)
			(layer "F.SilkS")
		)
		(fp_line
			(start -0.7874 0.4064)
			(end -0.7874 -0.4064)
			(stroke
				(width 0.1524)
				(type default)
			)
			(layer "F.SilkS")
		)
		(fp_line
			(start 0.7874 -0.4064)
			(end 0.7874 0.4064)
			(stroke
				(width 0.1524)
				(type default)
			)
			(layer "F.SilkS")
		)
		(fp_line
			(start 0.7874 0.4064)
			(end -0.7874 0.4064)
			(stroke
				(width 0.1524)
				(type default)
			)
			(layer "F.SilkS")
		)
		(fp_line
			(start -0.67945 -0.305054)
			(end -0.12065 -0.305054)
			(stroke
				(width 0.1)
				(type default)
			)
			(layer "F.Fab")
		)
		(fp_line
			(start -0.67945 0.3048)
			(end -0.67945 -0.305054)
			(stroke
				(width 0.1)
				(type default)
			)
			(layer "F.Fab")
		)
		(fp_line
			(start -0.12065 -0.305054)
			(end -0.12065 -0.2794)
			(stroke
				(width 0.1)
				(type default)
			)
			(layer "F.Fab")
		)
		(fp_line
			(start -0.12065 -0.2794)
			(end 0.12065 -0.2794)
			(stroke
				(width 0.1)
				(type default)
			)
			(layer "F.Fab")
		)
		(fp_line
			(start -0.12065 0.2794)
			(end -0.12065 0.3048)
			(stroke
				(width 0.1)
				(type default)
			)
			(layer "F.Fab")
		)
		(fp_line
			(start -0.12065 0.3048)
			(end -0.67945 0.3048)
			(stroke
				(width 0.1)
				(type default)
			)
			(layer "F.Fab")
		)
		(fp_line
			(start 0.120396 0.2794)
			(end -0.12065 0.2794)
			(stroke
				(width 0.1)
				(type default)
			)
			(layer "F.Fab")
		)
		(fp_line
			(start 0.120396 0.3048)
			(end 0.120396 0.2794)
			(stroke
				(width 0.1)
				(type default)
			)
			(layer "F.Fab")
		)
		(fp_line
			(start 0.12065 -0.3048)
			(end 0.67945 -0.3048)
			(stroke
				(width 0.1)
				(type default)
			)
			(layer "F.Fab")
		)
		(fp_line
			(start 0.12065 -0.2794)
			(end 0.12065 -0.3048)
			(stroke
				(width 0.1)
				(type default)
			)
			(layer "F.Fab")
		)
		(fp_line
			(start 0.67945 -0.3048)
			(end 0.67945 0.3048)
			(stroke
				(width 0.1)
				(type default)
			)
			(layer "F.Fab")
		)
		(fp_line
			(start 0.67945 0.3048)
			(end 0.120396 0.3048)
			(stroke
				(width 0.1)
				(type default)
			)
			(layer "F.Fab")
		)
		(pad "1" smd circle
			(at -0.40005 0)
			(size 0 0)
			(layers "F.Cu" "F.Mask" "F.Paste")
			(net "SMB_SCM_2_R5_SCL")
		)
		(pad "2" smd circle
			(at 0.40005 0)
			(size 0 0)
			(layers "F.Cu" "F.Mask" "F.Paste")
			(net "SMB_CLK_PVDDCR_CPU1_P0_R")
		)
	)
)
